(kicad_pcb
	(version 20260206)
	(generator "pcbnew")
	(generator_version "10.0")
	(general
		(thickness 1.6)
		(legacy_teardrops no)
	)
	(paper "A4")
	(title_block
		(title "03242023_DA0F0TMBIJ0_F0T_Motherboard_J_brd_V01_OCP.brd")
		(comment 1 "Grand Teton / footprints 2768-2774 of 6105")
	)
	(layers
		(0 "F.Cu" signal "TOP")
		(4 "In1.Cu" signal "GND")
		(6 "In2.Cu" signal "IN1")
		(8 "In3.Cu" signal "GND1")
		(10 "In4.Cu" signal "IN2")
		(12 "In5.Cu" signal "GND2")
		(14 "In6.Cu" signal "IN3")
		(16 "In7.Cu" signal "GND3")
		(18 "In8.Cu" signal "VCC")
		(20 "In9.Cu" signal "VCC1")
		(22 "In10.Cu" signal "GND4")
		(24 "In11.Cu" signal "IN4")
		(26 "In12.Cu" signal "GND5")
		(28 "In13.Cu" signal "IN5")
		(30 "In14.Cu" signal "GND6")
		(32 "In15.Cu" signal "IN6")
		(34 "In16.Cu" signal "GND7")
		(2 "B.Cu" signal "BOTTOM")
		(9 "F.Adhes" user "F.Adhesive")
		(11 "B.Adhes" user "B.Adhesive")
		(13 "F.Paste" user "Package Geometry/Pastemask Top")
		(15 "B.Paste" user "Package Geometry/Pastemask Bottom")
		(5 "F.SilkS" user "Ref Des/Silkscreen Top")
		(7 "B.SilkS" user "Ref Des/Silkscreen Bottom")
		(1 "F.Mask" user "Board Geometry/Soldermask Top")
		(3 "B.Mask" user "Board Geometry/Soldermask Bottom")
		(17 "Dwgs.User" user "User.Drawings")
		(19 "Cmts.User" user "User.Comments")
		(21 "Eco1.User" user "User.Eco1")
		(23 "Eco2.User" user "User.Eco2")
		(25 "Edge.Cuts" user "Board Geometry/Outline")
		(27 "Margin" user)
		(31 "F.CrtYd" user "Package Geometry/Place Bound Top")
		(29 "B.CrtYd" user "Package Geometry/Place Bound Bottom")
		(35 "F.Fab" user "Ref Des/Assembly Top")
		(33 "B.Fab" user "Ref Des/Assembly Bottom")
	)
	(footprint ""
		(layer "F.Cu")
		(at 380.538736 -92.887292 90)
		(property "Reference" "R1831"
			(at 0 0 90)
			(layer "F.SilkS")
			(hide yes)
			(effects
				(font
					(size 1.27 1.27)
				)
			)
		)
		(property "Value" ""
			(at 0 0 90)
			(layer "F.Fab")
			(effects
				(font
					(size 1.27 1.27)
				)
			)
		)
		(duplicate_pad_numbers_are_jumpers no)
		(fp_line
			(start 0.7874 -0.4064)
			(end 0.7874 0.4064)
			(stroke
				(width 0.1524)
				(type default)
			)
			(layer "F.SilkS")
		)
		(fp_line
			(start -0.7874 -0.4064)
			(end 0.7874 -0.4064)
			(stroke
				(width 0.1524)
				(type default)
			)
			(layer "F.SilkS")
		)
		(fp_line
			(start 0.7874 0.4064)
			(end -0.7874 0.4064)
			(stroke
				(width 0.1524)
				(type default)
			)
			(layer "F.SilkS")
		)
		(fp_line
			(start -0.7874 0.4064)
			(end -0.7874 -0.4064)
			(stroke
				(width 0.1524)
				(type default)
			)
			(layer "F.SilkS")
		)
		(fp_line
			(start -0.12065 -0.305054)
			(end -0.12065 -0.2794)
			(stroke
				(width 0.1)
				(type default)
			)
			(layer "F.Fab")
		)
		(fp_line
			(start -0.67945 -0.305054)
			(end -0.12065 -0.305054)
			(stroke
				(width 0.1)
				(type default)
			)
			(layer "F.Fab")
		)
		(fp_line
			(start 0.67945 -0.3048)
			(end 0.67945 0.3048)
			(stroke
				(width 0.1)
				(type default)
			)
			(layer "F.Fab")
		)
		(fp_line
			(start 0.12065 -0.3048)
			(end 0.67945 -0.3048)
			(stroke
				(width 0.1)
				(type default)
			)
			(layer "F.Fab")
		)
		(fp_line
			(start 0.12065 -0.2794)
			(end 0.12065 -0.3048)
			(stroke
				(width 0.1)
				(type default)
			)
			(layer "F.Fab")
		)
		(fp_line
			(start -0.12065 -0.2794)
			(end 0.12065 -0.2794)
			(stroke
				(width 0.1)
				(type default)
			)
			(layer "F.Fab")
		)
		(fp_line
			(start 0.120396 0.2794)
			(end -0.12065 0.2794)
			(stroke
				(width 0.1)
				(type default)
			)
			(layer "F.Fab")
		)
		(fp_line
			(start -0.12065 0.2794)
			(end -0.12065 0.3048)
			(stroke
				(width 0.1)
				(type default)
			)
			(layer "F.Fab")
		)
		(fp_line
			(start 0.67945 0.3048)
			(end 0.120396 0.3048)
			(stroke
				(width 0.1)
				(type default)
			)
			(layer "F.Fab")
		)
		(fp_line
			(start 0.120396 0.3048)
			(end 0.120396 0.2794)
			(stroke
				(width 0.1)
				(type default)
			)
			(layer "F.Fab")
		)
		(fp_line
			(start -0.12065 0.3048)
			(end -0.67945 0.3048)
			(stroke
				(width 0.1)
				(type default)
			)
			(layer "F.Fab")
		)
		(fp_line
			(start -0.67945 0.3048)
			(end -0.67945 -0.305054)
			(stroke
				(width 0.1)
				(type default)
			)
			(layer "F.Fab")
		)
		(pad "1" smd circle
			(at -0.40005 0 90)
			(size 0 0)
			(layers "F.Cu" "F.Mask" "F.Paste")
			(net "JTAG_DBP_BMC_PRDY_N")
		)
		(pad "2" smd circle
			(at 0.40005 0 90)
			(size 0 0)
			(layers "F.Cu" "F.Mask" "F.Paste")
			(net "JTAG_DBP_BMC_PRDY_R_N")
		)
	)
	(footprint ""
		(layer "F.Cu")
		(at 317.553848 -408.517344 -90)
		(property "Reference" "C910"
			(at 0 0 270)
			(layer "F.SilkS")
			(hide yes)
			(effects
				(font
					(size 1.27 1.27)
				)
			)
		)
		(property "Value" ""
			(at 0 0 270)
			(layer "F.Fab")
			(effects
				(font
					(size 1.27 1.27)
				)
			)
		)
		(duplicate_pad_numbers_are_jumpers no)
		(fp_line
			(start -0.299974 0.150114)
			(end -0.299974 -0.150114)
			(stroke
				(width 0.1)
				(type default)
			)
			(layer "F.Fab")
		)
		(fp_line
			(start 0.299974 0.150114)
			(end -0.299974 0.150114)
			(stroke
				(width 0.1)
				(type default)
			)
			(layer "F.Fab")
		)
		(fp_line
			(start -0.299974 -0.150114)
			(end 0.299974 -0.150114)
			(stroke
				(width 0.1)
				(type default)
			)
			(layer "F.Fab")
		)
		(fp_line
			(start 0.299974 -0.150114)
			(end 0.299974 0.150114)
			(stroke
				(width 0.1)
				(type default)
			)
			(layer "F.Fab")
		)
		(pad "1" smd rect
			(at -0.2667 0 270)
			(size 0.3048 0.381)
			(layers "F.Cu" "F.Mask" "F.Paste")
			(net "P5E_CPU0_PE0_TX_C_DN<11>")
		)
		(pad "2" smd rect
			(at 0.2667 0 270)
			(size 0.3048 0.381)
			(layers "F.Cu" "F.Mask" "F.Paste")
			(net "P5E_CPU0_PE0_TX_DN<11>")
		)
	)
	(footprint ""
		(layer "F.Cu")
		(at 160.28035 -43.832526 90)
		(property "Reference" "R4472"
			(at 0 0 90)
			(layer "F.SilkS")
			(hide yes)
			(effects
				(font
					(size 1.27 1.27)
				)
			)
		)
		(property "Value" ""
			(at 0 0 90)
			(layer "F.Fab")
			(effects
				(font
					(size 1.27 1.27)
				)
			)
		)
		(duplicate_pad_numbers_are_jumpers no)
		(fp_line
			(start 0.7874 -0.4064)
			(end 0.7874 0.4064)
			(stroke
				(width 0.1524)
				(type default)
			)
			(layer "F.SilkS")
		)
		(fp_line
			(start 0.7874 0.4064)
			(end -0.7874 0.4064)
			(stroke
				(width 0.1524)
				(type default)
			)
			(layer "F.SilkS")
		)
		(fp_line
			(start -0.12065 -0.305054)
			(end -0.12065 -0.2794)
			(stroke
				(width 0.1)
				(type default)
			)
			(layer "F.Fab")
		)
		(fp_line
			(start -0.67945 -0.305054)
			(end -0.12065 -0.305054)
			(stroke
				(width 0.1)
				(type default)
			)
			(layer "F.Fab")
		)
		(fp_line
			(start 0.67945 -0.3048)
			(end 0.67945 0.3048)
			(stroke
				(width 0.1)
				(type default)
			)
			(layer "F.Fab")
		)
		(fp_line
			(start 0.12065 -0.3048)
			(end 0.67945 -0.3048)
			(stroke
				(width 0.1)
				(type default)
			)
			(layer "F.Fab")
		)
		(fp_line
			(start 0.12065 -0.2794)
			(end 0.12065 -0.3048)
			(stroke
				(width 0.1)
				(type default)
			)
			(layer "F.Fab")
		)
		(fp_line
			(start -0.12065 -0.2794)
			(end 0.12065 -0.2794)
			(stroke
				(width 0.1)
				(type default)
			)
			(layer "F.Fab")
		)
		(fp_line
			(start 0.120396 0.2794)
			(end -0.12065 0.2794)
			(stroke
				(width 0.1)
				(type default)
			)
			(layer "F.Fab")
		)
		(fp_line
			(start -0.12065 0.2794)
			(end -0.12065 0.3048)
			(stroke
				(width 0.1)
				(type default)
			)
			(layer "F.Fab")
		)
		(fp_line
			(start 0.67945 0.3048)
			(end 0.120396 0.3048)
			(stroke
				(width 0.1)
				(type default)
			)
			(layer "F.Fab")
		)
		(fp_line
			(start 0.120396 0.3048)
			(end 0.120396 0.2794)
			(stroke
				(width 0.1)
				(type default)
			)
			(layer "F.Fab")
		)
		(fp_line
			(start -0.12065 0.3048)
			(end -0.67945 0.3048)
			(stroke
				(width 0.1)
				(type default)
			)
			(layer "F.Fab")
		)
		(fp_line
			(start -0.67945 0.3048)
			(end -0.67945 -0.305054)
			(stroke
				(width 0.1)
				(type default)
			)
			(layer "F.Fab")
		)
		(pad "1" smd rect
			(at -0.40005 0 270)
			(size 0.4572 0.508)
			(layers "F.Cu" "F.Mask" "F.Paste")
			(net "USB2_PCH_0_R_DN")
		)
		(pad "2" smd rect
			(at 0.40005 0 270)
			(size 0.4572 0.508)
			(layers "F.Cu" "F.Mask" "F.Paste")
			(net "USB2_0_DN")
		)
	)
	(footprint ""
		(layer "F.Cu")
		(at 148.1963 -48.283368)
		(property "Reference" "R4090"
			(at 0 0 0)
			(layer "F.SilkS")
			(hide yes)
			(effects
				(font
					(size 1.27 1.27)
				)
			)
		)
		(property "Value" ""
			(at 0 0 0)
			(layer "F.Fab")
			(effects
				(font
					(size 1.27 1.27)
				)
			)
		)
		(duplicate_pad_numbers_are_jumpers no)
		(fp_line
			(start -0.7874 -0.4064)
			(end 0.7874 -0.4064)
			(stroke
				(width 0.1524)
				(type default)
			)
			(layer "F.SilkS")
		)
		(fp_line
			(start -0.7874 0.4064)
			(end -0.7874 -0.4064)
			(stroke
				(width 0.1524)
				(type default)
			)
			(layer "F.SilkS")
		)
		(fp_line
			(start 0.7874 -0.4064)
			(end 0.7874 0.4064)
			(stroke
				(width 0.1524)
				(type default)
			)
			(layer "F.SilkS")
		)
		(fp_line
			(start 0.7874 0.4064)
			(end -0.7874 0.4064)
			(stroke
				(width 0.1524)
				(type default)
			)
			(layer "F.SilkS")
		)
		(fp_line
			(start -0.67945 -0.305054)
			(end -0.12065 -0.305054)
			(stroke
				(width 0.1)
				(type default)
			)
			(layer "F.Fab")
		)
		(fp_line
			(start -0.67945 0.3048)
			(end -0.67945 -0.305054)
			(stroke
				(width 0.1)
				(type default)
			)
			(layer "F.Fab")
		)
		(fp_line
			(start -0.12065 -0.305054)
			(end -0.12065 -0.2794)
			(stroke
				(width 0.1)
				(type default)
			)
			(layer "F.Fab")
		)
		(fp_line
			(start -0.12065 -0.2794)
			(end 0.12065 -0.2794)
			(stroke
				(width 0.1)
				(type default)
			)
			(layer "F.Fab")
		)
		(fp_line
			(start -0.12065 0.2794)
			(end -0.12065 0.3048)
			(stroke
				(width 0.1)
				(type default)
			)
			(layer "F.Fab")
		)
		(fp_line
			(start -0.12065 0.3048)
			(end -0.67945 0.3048)
			(stroke
				(width 0.1)
				(type default)
			)
			(layer "F.Fab")
		)
		(fp_line
			(start 0.120396 0.2794)
			(end -0.12065 0.2794)
			(stroke
				(width 0.1)
				(type default)
			)
			(layer "F.Fab")
		)
		(fp_line
			(start 0.120396 0.3048)
			(end 0.120396 0.2794)
			(stroke
				(width 0.1)
				(type default)
			)
			(layer "F.Fab")
		)
		(fp_line
			(start 0.12065 -0.3048)
			(end 0.67945 -0.3048)
			(stroke
				(width 0.1)
				(type default)
			)
			(layer "F.Fab")
		)
		(fp_line
			(start 0.12065 -0.2794)
			(end 0.12065 -0.3048)
			(stroke
				(width 0.1)
				(type default)
			)
			(layer "F.Fab")
		)
		(fp_line
			(start 0.67945 -0.3048)
			(end 0.67945 0.3048)
			(stroke
				(width 0.1)
				(type default)
			)
			(layer "F.Fab")
		)
		(fp_line
			(start 0.67945 0.3048)
			(end 0.120396 0.3048)
			(stroke
				(width 0.1)
				(type default)
			)
			(layer "F.Fab")
		)
		(pad "1" smd circle
			(at -0.40005 0)
			(size 0 0)
			(layers "F.Cu" "F.Mask" "F.Paste")
			(net "P3V3_AUX")
		)
		(pad "2" smd circle
			(at 0.40005 0)
			(size 0 0)
			(layers "F.Cu" "F.Mask" "F.Paste")
			(net "M2_0_P3V3_ADC_ALERT_R")
		)
	)
	(footprint ""
		(layer "F.Cu")
		(at 411.201108 -362.296964)
		(property "Reference" "PR632"
			(at 0 0 0)
			(layer "F.SilkS")
			(hide yes)
			(effects
				(font
					(size 1.27 1.27)
				)
			)
		)
		(property "Value" ""
			(at 0 0 0)
			(layer "F.Fab")
			(effects
				(font
					(size 1.27 1.27)
				)
			)
		)
		(duplicate_pad_numbers_are_jumpers no)
		(fp_line
			(start -0.7874 -0.4064)
			(end 0.7874 -0.4064)
			(stroke
				(width 0.1524)
				(type default)
			)
			(layer "F.SilkS")
		)
		(fp_line
			(start -0.7874 0.4064)
			(end -0.7874 -0.4064)
			(stroke
				(width 0.1524)
				(type default)
			)
			(layer "F.SilkS")
		)
		(fp_line
			(start 0.7874 -0.4064)
			(end 0.7874 0.4064)
			(stroke
				(width 0.1524)
				(type default)
			)
			(layer "F.SilkS")
		)
		(fp_line
			(start 0.7874 0.4064)
			(end -0.7874 0.4064)
			(stroke
				(width 0.1524)
				(type default)
			)
			(layer "F.SilkS")
		)
		(fp_line
			(start -0.67945 -0.305054)
			(end -0.12065 -0.305054)
			(stroke
				(width 0.1)
				(type default)
			)
			(layer "F.Fab")
		)
		(fp_line
			(start -0.67945 0.3048)
			(end -0.67945 -0.305054)
			(stroke
				(width 0.1)
				(type default)
			)
			(layer "F.Fab")
		)
		(fp_line
			(start -0.12065 -0.305054)
			(end -0.12065 -0.2794)
			(stroke
				(width 0.1)
				(type default)
			)
			(layer "F.Fab")
		)
		(fp_line
			(start -0.12065 -0.2794)
			(end 0.12065 -0.2794)
			(stroke
				(width 0.1)
				(type default)
			)
			(layer "F.Fab")
		)
		(fp_line
			(start -0.12065 0.2794)
			(end -0.12065 0.3048)
			(stroke
				(width 0.1)
				(type default)
			)
			(layer "F.Fab")
		)
		(fp_line
			(start -0.12065 0.3048)
			(end -0.67945 0.3048)
			(stroke
				(width 0.1)
				(type default)
			)
			(layer "F.Fab")
		)
		(fp_line
			(start 0.120396 0.2794)
			(end -0.12065 0.2794)
			(stroke
				(width 0.1)
				(type default)
			)
			(layer "F.Fab")
		)
		(fp_line
			(start 0.120396 0.3048)
			(end 0.120396 0.2794)
			(stroke
				(width 0.1)
				(type default)
			)
			(layer "F.Fab")
		)
		(fp_line
			(start 0.12065 -0.3048)
			(end 0.67945 -0.3048)
			(stroke
				(width 0.1)
				(type default)
			)
			(layer "F.Fab")
		)
		(fp_line
			(start 0.12065 -0.2794)
			(end 0.12065 -0.3048)
			(stroke
				(width 0.1)
				(type default)
			)
			(layer "F.Fab")
		)
		(fp_line
			(start 0.67945 -0.3048)
			(end 0.67945 0.3048)
			(stroke
				(width 0.1)
				(type default)
			)
			(layer "F.Fab")
		)
		(fp_line
			(start 0.67945 0.3048)
			(end 0.120396 0.3048)
			(stroke
				(width 0.1)
				(type default)
			)
			(layer "F.Fab")
		)
		(pad "1" smd circle
			(at -0.40005 0)
			(size 0 0)
			(layers "F.Cu" "F.Mask" "F.Paste")
			(net "P3V3")
		)
		(pad "2" smd circle
			(at 0.40005 0)
			(size 0 0)
			(layers "F.Cu" "F.Mask" "F.Paste")
			(net "PVCCFA_EHV_FIVRA_CPU0_PVCC1")
		)
	)
	(footprint ""
		(layer "F.Cu")
		(at 252.961648 -55.177182)
		(property "Reference" "PR3953"
			(at 0 0 0)
			(layer "F.SilkS")
			(hide yes)
			(effects
				(font
					(size 1.27 1.27)
				)
			)
		)
		(property "Value" ""
			(at 0 0 0)
			(layer "F.Fab")
			(effects
				(font
					(size 1.27 1.27)
				)
			)
		)
		(duplicate_pad_numbers_are_jumpers no)
		(fp_line
			(start -0.7874 -0.4064)
			(end 0.7874 -0.4064)
			(stroke
				(width 0.1524)
				(type default)
			)
			(layer "F.SilkS")
		)
		(fp_line
			(start -0.7874 0.4064)
			(end -0.7874 -0.4064)
			(stroke
				(width 0.1524)
				(type default)
			)
			(layer "F.SilkS")
		)
		(fp_line
			(start 0.7874 -0.4064)
			(end 0.7874 0.4064)
			(stroke
				(width 0.1524)
				(type default)
			)
			(layer "F.SilkS")
		)
		(fp_line
			(start 0.7874 0.4064)
			(end -0.7874 0.4064)
			(stroke
				(width 0.1524)
				(type default)
			)
			(layer "F.SilkS")
		)
		(fp_line
			(start -0.67945 -0.305054)
			(end -0.12065 -0.305054)
			(stroke
				(width 0.1)
				(type default)
			)
			(layer "F.Fab")
		)
		(fp_line
			(start -0.67945 0.3048)
			(end -0.67945 -0.305054)
			(stroke
				(width 0.1)
				(type default)
			)
			(layer "F.Fab")
		)
		(fp_line
			(start -0.12065 -0.305054)
			(end -0.12065 -0.2794)
			(stroke
				(width 0.1)
				(type default)
			)
			(layer "F.Fab")
		)
		(fp_line
			(start -0.12065 -0.2794)
			(end 0.12065 -0.2794)
			(stroke
				(width 0.1)
				(type default)
			)
			(layer "F.Fab")
		)
		(fp_line
			(start -0.12065 0.2794)
			(end -0.12065 0.3048)
			(stroke
				(width 0.1)
				(type default)
			)
			(layer "F.Fab")
		)
		(fp_line
			(start -0.12065 0.3048)
			(end -0.67945 0.3048)
			(stroke
				(width 0.1)
				(type default)
			)
			(layer "F.Fab")
		)
		(fp_line
			(start 0.120396 0.2794)
			(end -0.12065 0.2794)
			(stroke
				(width 0.1)
				(type default)
			)
			(layer "F.Fab")
		)
		(fp_line
			(start 0.120396 0.3048)
			(end 0.120396 0.2794)
			(stroke
				(width 0.1)
				(type default)
			)
			(layer "F.Fab")
		)
		(fp_line
			(start 0.12065 -0.3048)
			(end 0.67945 -0.3048)
			(stroke
				(width 0.1)
				(type default)
			)
			(layer "F.Fab")
		)
		(fp_line
			(start 0.12065 -0.2794)
			(end 0.12065 -0.3048)
			(stroke
				(width 0.1)
				(type default)
			)
			(layer "F.Fab")
		)
		(fp_line
			(start 0.67945 -0.3048)
			(end 0.67945 0.3048)
			(stroke
				(width 0.1)
				(type default)
			)
			(layer "F.Fab")
		)
		(fp_line
			(start 0.67945 0.3048)
			(end 0.120396 0.3048)
			(stroke
				(width 0.1)
				(type default)
			)
			(layer "F.Fab")
		)
		(pad "1" smd circle
			(at -0.40005 0)
			(size 0 0)
			(layers "F.Cu" "F.Mask" "F.Paste")
			(net "P12V_AUX")
		)
		(pad "2" smd circle
			(at 0.40005 0)
			(size 0 0)
			(layers "F.Cu" "F.Mask" "F.Paste")
			(net "P12V_E1S_OV_FB_0")
		)
	)
	(footprint ""
		(layer "F.Cu")
		(at 212.4202 -107.4166 90)
		(property "Reference" "R4776"
			(at 0 0 90)
			(layer "F.SilkS")
			(hide yes)
			(effects
				(font
					(size 1.27 1.27)
				)
			)
		)
		(property "Value" ""
			(at 0 0 90)
			(layer "F.Fab")
			(effects
				(font
					(size 1.27 1.27)
				)
			)
		)
		(duplicate_pad_numbers_are_jumpers no)
		(fp_line
			(start 0.7874 -0.4064)
			(end 0.7874 0.4064)
			(stroke
				(width 0.1524)
				(type default)
			)
			(layer "F.SilkS")
		)
		(fp_line
			(start -0.7874 -0.4064)
			(end 0.7874 -0.4064)
			(stroke
				(width 0.1524)
				(type default)
			)
			(layer "F.SilkS")
		)
		(fp_line
			(start 0.7874 0.4064)
			(end -0.7874 0.4064)
			(stroke
				(width 0.1524)
				(type default)
			)
			(layer "F.SilkS")
		)
		(fp_line
			(start -0.7874 0.4064)
			(end -0.7874 -0.4064)
			(stroke
				(width 0.1524)
				(type default)
			)
			(layer "F.SilkS")
		)
		(fp_line
			(start -0.12065 -0.305054)
			(end -0.12065 -0.2794)
			(stroke
				(width 0.1)
				(type default)
			)
			(layer "F.Fab")
		)
		(fp_line
			(start -0.67945 -0.305054)
			(end -0.12065 -0.305054)
			(stroke
				(width 0.1)
				(type default)
			)
			(layer "F.Fab")
		)
		(fp_line
			(start 0.67945 -0.3048)
			(end 0.67945 0.3048)
			(stroke
				(width 0.1)
				(type default)
			)
			(layer "F.Fab")
		)
		(fp_line
			(start 0.12065 -0.3048)
			(end 0.67945 -0.3048)
			(stroke
				(width 0.1)
				(type default)
			)
			(layer "F.Fab")
		)
		(fp_line
			(start 0.12065 -0.2794)
			(end 0.12065 -0.3048)
			(stroke
				(width 0.1)
				(type default)
			)
			(layer "F.Fab")
		)
		(fp_line
			(start -0.12065 -0.2794)
			(end 0.12065 -0.2794)
			(stroke
				(width 0.1)
				(type default)
			)
			(layer "F.Fab")
		)
		(fp_line
			(start 0.120396 0.2794)
			(end -0.12065 0.2794)
			(stroke
				(width 0.1)
				(type default)
			)
			(layer "F.Fab")
		)
		(fp_line
			(start -0.12065 0.2794)
			(end -0.12065 0.3048)
			(stroke
				(width 0.1)
				(type default)
			)
			(layer "F.Fab")
		)
		(fp_line
			(start 0.67945 0.3048)
			(end 0.120396 0.3048)
			(stroke
				(width 0.1)
				(type default)
			)
			(layer "F.Fab")
		)
		(fp_line
			(start 0.120396 0.3048)
			(end 0.120396 0.2794)
			(stroke
				(width 0.1)
				(type default)
			)
			(layer "F.Fab")
		)
		(fp_line
			(start -0.12065 0.3048)
			(end -0.67945 0.3048)
			(stroke
				(width 0.1)
				(type default)
			)
			(layer "F.Fab")
		)
		(fp_line
			(start -0.67945 0.3048)
			(end -0.67945 -0.305054)
			(stroke
				(width 0.1)
				(type default)
			)
			(layer "F.Fab")
		)
		(pad "1" smd circle
			(at -0.40005 0 90)
			(size 0 0)
			(layers "F.Cu" "F.Mask" "F.Paste")
			(net "P12V_AUX")
		)
		(pad "2" smd circle
			(at 0.40005 0 90)
			(size 0 0)
			(layers "F.Cu" "F.Mask" "F.Paste")
			(net "P12V_AUX_UV_TRIGGER")
		)
	)
)
